(kicad_pcb
	(version 20260206)
	(generator "pcbnew")
	(generator_version "10.0")
	(general
		(thickness 1.6)
		(legacy_teardrops no)
	)
	(paper "A4")
	(title_block
		(title "03242023_DA0F0TMBIJ0_F0T_Motherboard_J_brd_V01_OCP.brd")
		(comment 1 "Grand Teton / footprints 958-963 of 6105")
	)
	(layers
		(0 "F.Cu" signal "TOP")
		(4 "In1.Cu" signal "GND")
		(6 "In2.Cu" signal "IN1")
		(8 "In3.Cu" signal "GND1")
		(10 "In4.Cu" signal "IN2")
		(12 "In5.Cu" signal "GND2")
		(14 "In6.Cu" signal "IN3")
		(16 "In7.Cu" signal "GND3")
		(18 "In8.Cu" signal "VCC")
		(20 "In9.Cu" signal "VCC1")
		(22 "In10.Cu" signal "GND4")
		(24 "In11.Cu" signal "IN4")
		(26 "In12.Cu" signal "GND5")
		(28 "In13.Cu" signal "IN5")
		(30 "In14.Cu" signal "GND6")
		(32 "In15.Cu" signal "IN6")
		(34 "In16.Cu" signal "GND7")
		(2 "B.Cu" signal "BOTTOM")
		(9 "F.Adhes" user "F.Adhesive")
		(11 "B.Adhes" user "B.Adhesive")
		(13 "F.Paste" user "Package Geometry/Pastemask Top")
		(15 "B.Paste" user "Package Geometry/Pastemask Bottom")
		(5 "F.SilkS" user "Ref Des/Silkscreen Top")
		(7 "B.SilkS" user "Ref Des/Silkscreen Bottom")
		(1 "F.Mask" user "Board Geometry/Soldermask Top")
		(3 "B.Mask" user "Board Geometry/Soldermask Bottom")
		(17 "Dwgs.User" user "User.Drawings")
		(19 "Cmts.User" user "User.Comments")
		(21 "Eco1.User" user "User.Eco1")
		(23 "Eco2.User" user "User.Eco2")
		(25 "Edge.Cuts" user "Board Geometry/Outline")
		(27 "Margin" user)
		(31 "F.CrtYd" user "Package Geometry/Place Bound Top")
		(29 "B.CrtYd" user "Package Geometry/Place Bound Bottom")
		(35 "F.Fab" user "Ref Des/Assembly Top")
		(33 "B.Fab" user "Ref Des/Assembly Bottom")
	)
	(footprint ""
		(layer "F.Cu")
		(at 388.97433 -408.517344 -90)
		(property "Reference" "C881"
			(at 0 0 270)
			(layer "F.SilkS")
			(hide yes)
			(effects
				(font
					(size 1.27 1.27)
				)
			)
		)
		(property "Value" ""
			(at 0 0 270)
			(layer "F.Fab")
			(effects
				(font
					(size 1.27 1.27)
				)
			)
		)
		(duplicate_pad_numbers_are_jumpers no)
		(fp_line
			(start -0.299974 0.150114)
			(end -0.299974 -0.150114)
			(stroke
				(width 0.1)
				(type default)
			)
			(layer "F.Fab")
		)
		(fp_line
			(start 0.299974 0.150114)
			(end -0.299974 0.150114)
			(stroke
				(width 0.1)
				(type default)
			)
			(layer "F.Fab")
		)
		(fp_line
			(start -0.299974 -0.150114)
			(end 0.299974 -0.150114)
			(stroke
				(width 0.1)
				(type default)
			)
			(layer "F.Fab")
		)
		(fp_line
			(start 0.299974 -0.150114)
			(end 0.299974 0.150114)
			(stroke
				(width 0.1)
				(type default)
			)
			(layer "F.Fab")
		)
		(pad "1" smd rect
			(at -0.2667 0 270)
			(size 0.3048 0.381)
			(layers "F.Cu" "F.Mask" "F.Paste")
			(net "P5E_CPU0_PE3_TX_C_DP<10>")
		)
		(pad "2" smd rect
			(at 0.2667 0 270)
			(size 0.3048 0.381)
			(layers "F.Cu" "F.Mask" "F.Paste")
			(net "P5E_CPU0_PE3_TX_DP<10>")
		)
	)
	(footprint ""
		(layer "F.Cu")
		(at 193.38036 -116.804948 180)
		(property "Reference" "R3049"
			(at 0 0 180)
			(layer "F.SilkS")
			(hide yes)
			(effects
				(font
					(size 1.27 1.27)
				)
			)
		)
		(property "Value" ""
			(at 0 0 180)
			(layer "F.Fab")
			(effects
				(font
					(size 1.27 1.27)
				)
			)
		)
		(duplicate_pad_numbers_are_jumpers no)
		(fp_line
			(start 0.7874 0.4064)
			(end -0.7874 0.4064)
			(stroke
				(width 0.1524)
				(type default)
			)
			(layer "F.SilkS")
		)
		(fp_line
			(start 0.7874 -0.4064)
			(end 0.7874 0.4064)
			(stroke
				(width 0.1524)
				(type default)
			)
			(layer "F.SilkS")
		)
		(fp_line
			(start -0.7874 0.4064)
			(end -0.7874 -0.4064)
			(stroke
				(width 0.1524)
				(type default)
			)
			(layer "F.SilkS")
		)
		(fp_line
			(start -0.7874 -0.4064)
			(end 0.7874 -0.4064)
			(stroke
				(width 0.1524)
				(type default)
			)
			(layer "F.SilkS")
		)
		(fp_line
			(start 0.67945 0.3048)
			(end 0.120396 0.3048)
			(stroke
				(width 0.1)
				(type default)
			)
			(layer "F.Fab")
		)
		(fp_line
			(start 0.67945 -0.3048)
			(end 0.67945 0.3048)
			(stroke
				(width 0.1)
				(type default)
			)
			(layer "F.Fab")
		)
		(fp_line
			(start 0.12065 -0.2794)
			(end 0.12065 -0.3048)
			(stroke
				(width 0.1)
				(type default)
			)
			(layer "F.Fab")
		)
		(fp_line
			(start 0.12065 -0.3048)
			(end 0.67945 -0.3048)
			(stroke
				(width 0.1)
				(type default)
			)
			(layer "F.Fab")
		)
		(fp_line
			(start 0.120396 0.3048)
			(end 0.120396 0.2794)
			(stroke
				(width 0.1)
				(type default)
			)
			(layer "F.Fab")
		)
		(fp_line
			(start 0.120396 0.2794)
			(end -0.12065 0.2794)
			(stroke
				(width 0.1)
				(type default)
			)
			(layer "F.Fab")
		)
		(fp_line
			(start -0.12065 0.3048)
			(end -0.67945 0.3048)
			(stroke
				(width 0.1)
				(type default)
			)
			(layer "F.Fab")
		)
		(fp_line
			(start -0.12065 0.2794)
			(end -0.12065 0.3048)
			(stroke
				(width 0.1)
				(type default)
			)
			(layer "F.Fab")
		)
		(fp_line
			(start -0.12065 -0.2794)
			(end 0.12065 -0.2794)
			(stroke
				(width 0.1)
				(type default)
			)
			(layer "F.Fab")
		)
		(fp_line
			(start -0.12065 -0.305054)
			(end -0.12065 -0.2794)
			(stroke
				(width 0.1)
				(type default)
			)
			(layer "F.Fab")
		)
		(fp_line
			(start -0.67945 0.3048)
			(end -0.67945 -0.305054)
			(stroke
				(width 0.1)
				(type default)
			)
			(layer "F.Fab")
		)
		(fp_line
			(start -0.67945 -0.305054)
			(end -0.12065 -0.305054)
			(stroke
				(width 0.1)
				(type default)
			)
			(layer "F.Fab")
		)
		(pad "1" smd circle
			(at -0.40005 0 180)
			(size 0 0)
			(layers "F.Cu" "F.Mask" "F.Paste")
			(net "IRQ_SML1_PMBUS_ALERT_N")
		)
		(pad "2" smd circle
			(at 0.40005 0 180)
			(size 0 0)
			(layers "F.Cu" "F.Mask" "F.Paste")
			(net "IRQ_PSU_ALERT_R_N")
		)
	)
	(footprint ""
		(layer "F.Cu")
		(at 365.46663 -256.654046 -90)
		(property "Reference" "C988"
			(at 0 0 270)
			(layer "F.SilkS")
			(hide yes)
			(effects
				(font
					(size 1.27 1.27)
				)
			)
		)
		(property "Value" ""
			(at 0 0 270)
			(layer "F.Fab")
			(effects
				(font
					(size 1.27 1.27)
				)
			)
		)
		(duplicate_pad_numbers_are_jumpers no)
		(fp_line
			(start -0.7874 0.4064)
			(end -0.7874 -0.4064)
			(stroke
				(width 0.1524)
				(type default)
			)
			(layer "F.SilkS")
		)
		(fp_line
			(start 0.7874 0.4064)
			(end -0.7874 0.4064)
			(stroke
				(width 0.1524)
				(type default)
			)
			(layer "F.SilkS")
		)
		(fp_line
			(start -0.7874 -0.4064)
			(end 0.7874 -0.4064)
			(stroke
				(width 0.1524)
				(type default)
			)
			(layer "F.SilkS")
		)
		(fp_line
			(start 0.7874 -0.4064)
			(end 0.7874 0.4064)
			(stroke
				(width 0.1524)
				(type default)
			)
			(layer "F.SilkS")
		)
		(fp_line
			(start -0.67945 0.3048)
			(end -0.67945 -0.305054)
			(stroke
				(width 0.1)
				(type default)
			)
			(layer "F.Fab")
		)
		(fp_line
			(start -0.12065 0.3048)
			(end -0.67945 0.3048)
			(stroke
				(width 0.1)
				(type default)
			)
			(layer "F.Fab")
		)
		(fp_line
			(start 0.120396 0.3048)
			(end 0.120396 0.2794)
			(stroke
				(width 0.1)
				(type default)
			)
			(layer "F.Fab")
		)
		(fp_line
			(start 0.67945 0.3048)
			(end 0.120396 0.3048)
			(stroke
				(width 0.1)
				(type default)
			)
			(layer "F.Fab")
		)
		(fp_line
			(start -0.12065 0.2794)
			(end -0.12065 0.3048)
			(stroke
				(width 0.1)
				(type default)
			)
			(layer "F.Fab")
		)
		(fp_line
			(start 0.120396 0.2794)
			(end -0.12065 0.2794)
			(stroke
				(width 0.1)
				(type default)
			)
			(layer "F.Fab")
		)
		(fp_line
			(start -0.12065 -0.2794)
			(end 0.12065 -0.2794)
			(stroke
				(width 0.1)
				(type default)
			)
			(layer "F.Fab")
		)
		(fp_line
			(start 0.12065 -0.2794)
			(end 0.12065 -0.3048)
			(stroke
				(width 0.1)
				(type default)
			)
			(layer "F.Fab")
		)
		(fp_line
			(start 0.12065 -0.3048)
			(end 0.67945 -0.3048)
			(stroke
				(width 0.1)
				(type default)
			)
			(layer "F.Fab")
		)
		(fp_line
			(start 0.67945 -0.3048)
			(end 0.67945 0.3048)
			(stroke
				(width 0.1)
				(type default)
			)
			(layer "F.Fab")
		)
		(fp_line
			(start -0.67945 -0.305054)
			(end -0.12065 -0.305054)
			(stroke
				(width 0.1)
				(type default)
			)
			(layer "F.Fab")
		)
		(fp_line
			(start -0.12065 -0.305054)
			(end -0.12065 -0.2794)
			(stroke
				(width 0.1)
				(type default)
			)
			(layer "F.Fab")
		)
		(pad "1" smd circle
			(at -0.40005 0 270)
			(size 0 0)
			(layers "F.Cu" "F.Mask" "F.Paste")
			(net "PVCCIN_CPU0")
		)
		(pad "2" smd circle
			(at 0.40005 0 270)
			(size 0 0)
			(layers "F.Cu" "F.Mask" "F.Paste")
			(net "GND")
		)
	)
	(footprint ""
		(layer "F.Cu")
		(at 46.096428 -390.007348)
		(property "Reference" "R4646"
			(at 0 0 0)
			(layer "F.SilkS")
			(hide yes)
			(effects
				(font
					(size 1.27 1.27)
				)
			)
		)
		(property "Value" ""
			(at 0 0 0)
			(layer "F.Fab")
			(effects
				(font
					(size 1.27 1.27)
				)
			)
		)
		(duplicate_pad_numbers_are_jumpers no)
		(fp_line
			(start -0.7874 -0.4064)
			(end 0.7874 -0.4064)
			(stroke
				(width 0.1524)
				(type default)
			)
			(layer "F.SilkS")
		)
		(fp_line
			(start -0.7874 0.4064)
			(end -0.7874 -0.4064)
			(stroke
				(width 0.1524)
				(type default)
			)
			(layer "F.SilkS")
		)
		(fp_line
			(start 0.7874 -0.4064)
			(end 0.7874 0.4064)
			(stroke
				(width 0.1524)
				(type default)
			)
			(layer "F.SilkS")
		)
		(fp_line
			(start 0.7874 0.4064)
			(end -0.7874 0.4064)
			(stroke
				(width 0.1524)
				(type default)
			)
			(layer "F.SilkS")
		)
		(fp_line
			(start -0.67945 -0.305054)
			(end -0.12065 -0.305054)
			(stroke
				(width 0.1)
				(type default)
			)
			(layer "F.Fab")
		)
		(fp_line
			(start -0.67945 0.3048)
			(end -0.67945 -0.305054)
			(stroke
				(width 0.1)
				(type default)
			)
			(layer "F.Fab")
		)
		(fp_line
			(start -0.12065 -0.305054)
			(end -0.12065 -0.2794)
			(stroke
				(width 0.1)
				(type default)
			)
			(layer "F.Fab")
		)
		(fp_line
			(start -0.12065 -0.2794)
			(end 0.12065 -0.2794)
			(stroke
				(width 0.1)
				(type default)
			)
			(layer "F.Fab")
		)
		(fp_line
			(start -0.12065 0.2794)
			(end -0.12065 0.3048)
			(stroke
				(width 0.1)
				(type default)
			)
			(layer "F.Fab")
		)
		(fp_line
			(start -0.12065 0.3048)
			(end -0.67945 0.3048)
			(stroke
				(width 0.1)
				(type default)
			)
			(layer "F.Fab")
		)
		(fp_line
			(start 0.120396 0.2794)
			(end -0.12065 0.2794)
			(stroke
				(width 0.1)
				(type default)
			)
			(layer "F.Fab")
		)
		(fp_line
			(start 0.120396 0.3048)
			(end 0.120396 0.2794)
			(stroke
				(width 0.1)
				(type default)
			)
			(layer "F.Fab")
		)
		(fp_line
			(start 0.12065 -0.3048)
			(end 0.67945 -0.3048)
			(stroke
				(width 0.1)
				(type default)
			)
			(layer "F.Fab")
		)
		(fp_line
			(start 0.12065 -0.2794)
			(end 0.12065 -0.3048)
			(stroke
				(width 0.1)
				(type default)
			)
			(layer "F.Fab")
		)
		(fp_line
			(start 0.67945 -0.3048)
			(end 0.67945 0.3048)
			(stroke
				(width 0.1)
				(type default)
			)
			(layer "F.Fab")
		)
		(fp_line
			(start 0.67945 0.3048)
			(end 0.120396 0.3048)
			(stroke
				(width 0.1)
				(type default)
			)
			(layer "F.Fab")
		)
		(pad "1" smd circle
			(at -0.40005 0)
			(size 0 0)
			(layers "F.Cu" "F.Mask" "F.Paste")
			(net "FM_P2E_BUF2_EQB0")
		)
		(pad "2" smd circle
			(at 0.40005 0)
			(size 0 0)
			(layers "F.Cu" "F.Mask" "F.Paste")
			(net "GND")
		)
	)
	(footprint ""
		(layer "F.Cu")
		(at 441.353194 -375.662698 90)
		(property "Reference" "Q57"
			(at -0.4699 -6.276594 0)
			(unlocked yes)
			(layer "F.SilkS")
			(effects
				(font
					(size 0.7874 0.5842)
					(thickness 0.1524)
				)
				(justify left)
			)
		)
		(property "Value" ""
			(at 0 0 90)
			(layer "F.Fab")
			(effects
				(font
					(size 1.27 1.27)
				)
			)
		)
		(duplicate_pad_numbers_are_jumpers no)
		(fp_line
			(start 2.350008 -2.649982)
			(end 2.350008 -2.4892)
			(stroke
				(width 0.1524)
				(type default)
			)
			(layer "F.SilkS")
		)
		(fp_line
			(start -2.350008 -2.649982)
			(end 2.350008 -2.649982)
			(stroke
				(width 0.1524)
				(type default)
			)
			(layer "F.SilkS")
		)
		(fp_line
			(start -2.350008 -2.4384)
			(end -2.350008 -2.649982)
			(stroke
				(width 0.1524)
				(type default)
			)
			(layer "F.SilkS")
		)
		(fp_line
			(start 2.350008 2.4892)
			(end 2.350008 2.649982)
			(stroke
				(width 0.1524)
				(type default)
			)
			(layer "F.SilkS")
		)
		(fp_line
			(start 2.350008 2.649982)
			(end -2.350008 2.649982)
			(stroke
				(width 0.1524)
				(type default)
			)
			(layer "F.SilkS")
		)
		(fp_line
			(start -2.350008 2.649982)
			(end -2.350008 2.413)
			(stroke
				(width 0.1524)
				(type default)
			)
			(layer "F.SilkS")
		)
		(fp_poly
			(pts
				(xy -4.441444 -2.00914) (xy -5.482844 -1.62814) (xy -5.482844 -2.42824)
			)
			(stroke
				(width 0)
				(type default)
			)
			(fill yes)
			(layer "F.SilkS")
		)
		(fp_line
			(start 2.350008 -2.649982)
			(end 2.350008 2.649982)
			(stroke
				(width 0.1)
				(type default)
			)
			(layer "F.Fab")
		)
		(fp_line
			(start -2.350008 -2.649982)
			(end 2.350008 -2.649982)
			(stroke
				(width 0.1)
				(type default)
			)
			(layer "F.Fab")
		)
		(fp_line
			(start 2.350008 2.649982)
			(end -2.350008 2.649982)
			(stroke
				(width 0.1)
				(type default)
			)
			(layer "F.Fab")
		)
		(fp_line
			(start -2.350008 2.649982)
			(end -2.350008 -2.649982)
			(stroke
				(width 0.1)
				(type default)
			)
			(layer "F.Fab")
		)
		(fp_poly
			(pts
				(xy -3.717544 -1.905) (xy -4.758944 -2.3241) (xy -4.758944 -1.524)
			)
			(stroke
				(width 0)
				(type default)
			)
			(fill yes)
			(layer "F.Fab")
		)
		(pad "1" smd rect
			(at -2.999994 -1.905)
			(size 0.7112 1.1684)
			(layers "F.Cu" "F.Mask" "F.Paste")
			(net "P5V")
		)
		(pad "2" smd rect
			(at -2.999994 -0.635)
			(size 0.7112 1.1684)
			(layers "F.Cu" "F.Mask" "F.Paste")
			(net "P5V")
		)
		(pad "3" smd rect
			(at -2.999994 0.635)
			(size 0.7112 1.1684)
			(layers "F.Cu" "F.Mask" "F.Paste")
			(net "P5V")
		)
		(pad "4" smd rect
			(at -2.999994 1.905)
			(size 0.7112 1.1684)
			(layers "F.Cu" "F.Mask" "F.Paste")
			(net "VR_P5V_EN_D_R")
		)
		(pad "5" smd circle
			(at 0.925068 0)
			(size 0 0)
			(layers "F.Cu" "F.Mask" "F.Paste")
			(net "P5V_AUX")
		)
		(zone
			(layer "F.Cu")
			(hatch none 0.5)
			(connect_pads
				(clearance 0)
			)
			(min_thickness 0.25)
			(keepout
				(tracks not_allowed)
				(vias allowed)
				(pads allowed)
				(copperpour not_allowed)
				(footprints allowed)
			)
			(placement
				(enabled no)
				(sheetname "")
			)
			(fill
				(thermal_gap 0.5)
				(thermal_bridge_width 0.5)
				(island_removal_mode 0)
			)
			(polygon
				(pts
					(xy 439.194194 -374.272048) (xy 439.194194 -374.214898) (xy 443.512194 -374.214898) (xy 443.512194 -374.277128)
					(xy 443.994794 -374.277128) (xy 443.994794 -373.313198) (xy 438.711594 -373.313198) (xy 438.711594 -374.272048)
				)
			)
		)
	)
	(footprint ""
		(layer "F.Cu")
		(at 77.910944 -74.901552 -90)
		(property "Reference" "R3087"
			(at 0 0 270)
			(layer "F.SilkS")
			(hide yes)
			(effects
				(font
					(size 1.27 1.27)
				)
			)
		)
		(property "Value" ""
			(at 0 0 270)
			(layer "F.Fab")
			(effects
				(font
					(size 1.27 1.27)
				)
			)
		)
		(duplicate_pad_numbers_are_jumpers no)
		(fp_line
			(start -0.7874 0.4064)
			(end -0.7874 -0.4064)
			(stroke
				(width 0.1524)
				(type default)
			)
			(layer "F.SilkS")
		)
		(fp_line
			(start 0.7874 0.4064)
			(end -0.7874 0.4064)
			(stroke
				(width 0.1524)
				(type default)
			)
			(layer "F.SilkS")
		)
		(fp_line
			(start -0.7874 -0.4064)
			(end 0.7874 -0.4064)
			(stroke
				(width 0.1524)
				(type default)
			)
			(layer "F.SilkS")
		)
		(fp_line
			(start 0.7874 -0.4064)
			(end 0.7874 0.4064)
			(stroke
				(width 0.1524)
				(type default)
			)
			(layer "F.SilkS")
		)
		(fp_line
			(start -0.67945 0.3048)
			(end -0.67945 -0.305054)
			(stroke
				(width 0.1)
				(type default)
			)
			(layer "F.Fab")
		)
		(fp_line
			(start -0.12065 0.3048)
			(end -0.67945 0.3048)
			(stroke
				(width 0.1)
				(type default)
			)
			(layer "F.Fab")
		)
		(fp_line
			(start 0.120396 0.3048)
			(end 0.120396 0.2794)
			(stroke
				(width 0.1)
				(type default)
			)
			(layer "F.Fab")
		)
		(fp_line
			(start 0.67945 0.3048)
			(end 0.120396 0.3048)
			(stroke
				(width 0.1)
				(type default)
			)
			(layer "F.Fab")
		)
		(fp_line
			(start -0.12065 0.2794)
			(end -0.12065 0.3048)
			(stroke
				(width 0.1)
				(type default)
			)
			(layer "F.Fab")
		)
		(fp_line
			(start 0.120396 0.2794)
			(end -0.12065 0.2794)
			(stroke
				(width 0.1)
				(type default)
			)
			(layer "F.Fab")
		)
		(fp_line
			(start -0.12065 -0.2794)
			(end 0.12065 -0.2794)
			(stroke
				(width 0.1)
				(type default)
			)
			(layer "F.Fab")
		)
		(fp_line
			(start 0.12065 -0.2794)
			(end 0.12065 -0.3048)
			(stroke
				(width 0.1)
				(type default)
			)
			(layer "F.Fab")
		)
		(fp_line
			(start 0.12065 -0.3048)
			(end 0.67945 -0.3048)
			(stroke
				(width 0.1)
				(type default)
			)
			(layer "F.Fab")
		)
		(fp_line
			(start 0.67945 -0.3048)
			(end 0.67945 0.3048)
			(stroke
				(width 0.1)
				(type default)
			)
			(layer "F.Fab")
		)
		(fp_line
			(start -0.67945 -0.305054)
			(end -0.12065 -0.305054)
			(stroke
				(width 0.1)
				(type default)
			)
			(layer "F.Fab")
		)
		(fp_line
			(start -0.12065 -0.305054)
			(end -0.12065 -0.2794)
			(stroke
				(width 0.1)
				(type default)
			)
			(layer "F.Fab")
		)
		(pad "1" smd circle
			(at -0.40005 0 270)
			(size 0 0)
			(layers "F.Cu" "F.Mask" "F.Paste")
			(net "LED_PWRGD_PVPP_HBM_CPU0")
		)
		(pad "2" smd circle
			(at 0.40005 0 270)
			(size 0 0)
			(layers "F.Cu" "F.Mask" "F.Paste")
			(net "P3V3_AUX")
		)
	)
)
